# S9S_MB_2U (Grand Teton) — schematic netlist excerpt (pin names and nets, part order shuffled) for the footprints in the layout excerpt that follows; sources: Cadence DE-HDL packaged netlist, KiCad conversion of 03242023_DA0F0TMBIJ0_F0T_Motherboard_J_brd_V01_OCP.brd

PR4252  Q_RES  0 5% CHIP  pkg 0402LF  page 296 : A = NC_PVCCD_HV_CPU1_ACSP3 ; B = GND
C3270  Q_CAP  10UF 4V 20% EMPTY  pkg C0603  page 266 : A = PVNN_TERM_CPU0 ; B = GND

(kicad_pcb
	(version 20260206)
	(generator "pcbnew")
	(generator_version "10.0")
	(general
		(thickness 1.6)
		(legacy_teardrops no)
	)
	(paper "A4")
	(title_block
		(title "03242023_DA0F0TMBIJ0_F0T_Motherboard_J_brd_V01_OCP.brd")
		(comment 1 "Grand Teton / footprints 4538-4539 of 6105")
	)
	(layers
		(0 "F.Cu" signal "TOP")
		(4 "In1.Cu" signal "GND")
		(6 "In2.Cu" signal "IN1")
		(8 "In3.Cu" signal "GND1")
		(10 "In4.Cu" signal "IN2")
		(12 "In5.Cu" signal "GND2")
		(14 "In6.Cu" signal "IN3")
		(16 "In7.Cu" signal "GND3")
		(18 "In8.Cu" signal "VCC")
		(20 "In9.Cu" signal "VCC1")
		(22 "In10.Cu" signal "GND4")
		(24 "In11.Cu" signal "IN4")
		(26 "In12.Cu" signal "GND5")
		(28 "In13.Cu" signal "IN5")
		(30 "In14.Cu" signal "GND6")
		(32 "In15.Cu" signal "IN6")
		(34 "In16.Cu" signal "GND7")
		(2 "B.Cu" signal "BOTTOM")
		(9 "F.Adhes" user "F.Adhesive")
		(11 "B.Adhes" user "B.Adhesive")
		(13 "F.Paste" user "Package Geometry/Pastemask Top")
		(15 "B.Paste" user "Package Geometry/Pastemask Bottom")
		(5 "F.SilkS" user "Ref Des/Silkscreen Top")
		(7 "B.SilkS" user "Ref Des/Silkscreen Bottom")
		(1 "F.Mask" user "Board Geometry/Soldermask Top")
		(3 "B.Mask" user "Board Geometry/Soldermask Bottom")
		(17 "Dwgs.User" user "User.Drawings")
		(19 "Cmts.User" user "User.Comments")
		(21 "Eco1.User" user "User.Eco1")
		(23 "Eco2.User" user "User.Eco2")
		(25 "Edge.Cuts" user "Board Geometry/Outline")
		(27 "Margin" user)
		(31 "F.CrtYd" user "Package Geometry/Place Bound Top")
		(29 "B.CrtYd" user "Package Geometry/Place Bound Bottom")
		(35 "F.Fab" user "Ref Des/Assembly Top")
		(33 "B.Fab" user "Ref Des/Assembly Bottom")
	)
	(footprint ""
		(layer "B.Cu")
		(at 24.887682 -164.086286 180)
		(property "Reference" "PR4252"
			(at 0 0 0)
			(layer "B.SilkS")
			(hide yes)
			(effects
				(font
					(size 1.27 1.27)
				)
				(justify mirror)
			)
		)
		(property "Value" ""
			(at 0 0 0)
			(layer "B.Fab")
			(effects
				(font
					(size 1.27 1.27)
				)
				(justify mirror)
			)
		)
		(duplicate_pad_numbers_are_jumpers no)
		(fp_line
			(start 0.7874 0.4064)
			(end 0.7874 -0.4064)
			(stroke
				(width 0.1524)
				(type default)
			)
			(layer "B.SilkS")
		)
		(fp_line
			(start 0.7874 -0.4064)
			(end -0.7874 -0.4064)
			(stroke
				(width 0.1524)
				(type default)
			)
			(layer "B.SilkS")
		)
		(fp_line
			(start -0.7874 0.4064)
			(end 0.7874 0.4064)
			(stroke
				(width 0.1524)
				(type default)
			)
			(layer "B.SilkS")
		)
		(fp_line
			(start -0.7874 -0.4064)
			(end -0.7874 0.4064)
			(stroke
				(width 0.1524)
				(type default)
			)
			(layer "B.SilkS")
		)
		(fp_line
			(start 0.67945 0.3048)
			(end 0.67945 -0.305054)
			(stroke
				(width 0.1)
				(type default)
			)
			(layer "B.Fab")
		)
		(fp_line
			(start 0.67945 -0.305054)
			(end 0.12065 -0.305054)
			(stroke
				(width 0.1)
				(type default)
			)
			(layer "B.Fab")
		)
		(fp_line
			(start 0.12065 0.3048)
			(end 0.67945 0.3048)
			(stroke
				(width 0.1)
				(type default)
			)
			(layer "B.Fab")
		)
		(fp_line
			(start 0.12065 0.2794)
			(end 0.12065 0.3048)
			(stroke
				(width 0.1)
				(type default)
			)
			(layer "B.Fab")
		)
		(fp_line
			(start 0.12065 -0.2794)
			(end -0.12065 -0.2794)
			(stroke
				(width 0.1)
				(type default)
			)
			(layer "B.Fab")
		)
		(fp_line
			(start 0.12065 -0.305054)
			(end 0.12065 -0.2794)
			(stroke
				(width 0.1)
				(type default)
			)
			(layer "B.Fab")
		)
		(fp_line
			(start -0.120396 0.3048)
			(end -0.120396 0.2794)
			(stroke
				(width 0.1)
				(type default)
			)
			(layer "B.Fab")
		)
		(fp_line
			(start -0.120396 0.2794)
			(end 0.12065 0.2794)
			(stroke
				(width 0.1)
				(type default)
			)
			(layer "B.Fab")
		)
		(fp_line
			(start -0.12065 -0.2794)
			(end -0.12065 -0.3048)
			(stroke
				(width 0.1)
				(type default)
			)
			(layer "B.Fab")
		)
		(fp_line
			(start -0.12065 -0.3048)
			(end -0.67945 -0.3048)
			(stroke
				(width 0.1)
				(type default)
			)
			(layer "B.Fab")
		)
		(fp_line
			(start -0.67945 0.3048)
			(end -0.120396 0.3048)
			(stroke
				(width 0.1)
				(type default)
			)
			(layer "B.Fab")
		)
		(fp_line
			(start -0.67945 -0.3048)
			(end -0.67945 0.3048)
			(stroke
				(width 0.1)
				(type default)
			)
			(layer "B.Fab")
		)
		(pad "1" smd circle
			(at 0.40005 0)
			(size 0 0)
			(layers "B.Cu" "B.Mask" "B.Paste")
			(net "NC_PVCCD_HV_CPU1_ACSP3")
		)
		(pad "2" smd circle
			(at -0.40005 0)
			(size 0 0)
			(layers "B.Cu" "B.Mask" "B.Paste")
			(net "GND")
		)
	)
	(footprint ""
		(layer "B.Cu")
		(at 349.028004 -357.239316 180)
		(property "Reference" "C3270"
			(at 0 0 0)
			(layer "B.SilkS")
			(hide yes)
			(effects
				(font
					(size 1.27 1.27)
				)
				(justify mirror)
			)
		)
		(property "Value" ""
			(at 0 0 0)
			(layer "B.Fab")
			(effects
				(font
					(size 1.27 1.27)
				)
				(justify mirror)
			)
		)
		(duplicate_pad_numbers_are_jumpers no)
		(fp_line
			(start 1.2954 0.5842)
			(end 1.2954 -0.5842)
			(stroke
				(width 0.1524)
				(type default)
			)
			(layer "B.SilkS")
		)
		(fp_line
			(start 1.2954 -0.5842)
			(end -1.2954 -0.5842)
			(stroke
				(width 0.1524)
				(type default)
			)
			(layer "B.SilkS")
		)
		(fp_line
			(start 0 -0.5842)
			(end 0 0.5842)
			(stroke
				(width 0.1524)
				(type default)
			)
			(layer "B.SilkS")
		)
		(fp_line
			(start -1.2954 0.5842)
			(end 1.2954 0.5842)
			(stroke
				(width 0.1524)
				(type default)
			)
			(layer "B.SilkS")
		)
		(fp_line
			(start -1.2954 -0.5842)
			(end -1.2954 0.5842)
			(stroke
				(width 0.1524)
				(type default)
			)
			(layer "B.SilkS")
		)
		(fp_line
			(start 1.1938 0.4064)
			(end 1.1938 -0.4064)
			(stroke
				(width 0.1)
				(type default)
			)
			(layer "B.Fab")
		)
		(fp_line
			(start 1.1938 -0.4064)
			(end 0.8636 -0.4064)
			(stroke
				(width 0.1)
				(type default)
			)
			(layer "B.Fab")
		)
		(fp_line
			(start 0.8636 0.4572)
			(end 0.8636 0.4064)
			(stroke
				(width 0.1)
				(type default)
			)
			(layer "B.Fab")
		)
		(fp_line
			(start 0.8636 0.4064)
			(end 1.1938 0.4064)
			(stroke
				(width 0.1)
				(type default)
			)
			(layer "B.Fab")
		)
		(fp_line
			(start 0.8636 -0.4064)
			(end 0.8636 -0.4572)
			(stroke
				(width 0.1)
				(type default)
			)
			(layer "B.Fab")
		)
		(fp_line
			(start 0.8636 -0.4572)
			(end -0.8636 -0.4572)
			(stroke
				(width 0.1)
				(type default)
			)
			(layer "B.Fab")
		)
		(fp_line
			(start -0.8636 0.4572)
			(end 0.8636 0.4572)
			(stroke
				(width 0.1)
				(type default)
			)
			(layer "B.Fab")
		)
		(fp_line
			(start -0.8636 0.4064)
			(end -0.8636 0.4572)
			(stroke
				(width 0.1)
				(type default)
			)
			(layer "B.Fab")
		)
		(fp_line
			(start -0.8636 -0.4064)
			(end -1.1938 -0.4064)
			(stroke
				(width 0.1)
				(type default)
			)
			(layer "B.Fab")
		)
		(fp_line
			(start -0.8636 -0.4572)
			(end -0.8636 -0.4064)
			(stroke
				(width 0.1)
				(type default)
			)
			(layer "B.Fab")
		)
		(fp_line
			(start -1.1938 0.4064)
			(end -0.8636 0.4064)
			(stroke
				(width 0.1)
				(type default)
			)
			(layer "B.Fab")
		)
		(fp_line
			(start -1.1938 -0.4064)
			(end -1.1938 0.4064)
			(stroke
				(width 0.1)
				(type default)
			)
			(layer "B.Fab")
		)
		(pad "1" smd rect
			(at 0.7366 0 90)
			(size 0.7112 0.8128)
			(layers "B.Cu" "B.Mask" "B.Paste")
			(net "PVNN_TERM_CPU0")
		)
		(pad "2" smd rect
			(at -0.7366 0 90)
			(size 0.7112 0.8128)
			(layers "B.Cu" "B.Mask" "B.Paste")
			(net "GND")
		)
	)
)
